(kicad_pcb
	(version 20260206)
	(generator "pcbnew")
	(generator_version "10.0")
	(general
		(thickness 1.6)
		(legacy_teardrops no)
	)
	(paper "A4")
	(title_block
		(title "01162023_DA0F0TEBIF0_F0T_Expander_BD_F_brd_V02_OCP.brd")
		(comment 1 "Grand Teton / footprints 5917-5922 of 9728")
	)
	(layers
		(0 "F.Cu" signal "TOP")
		(4 "In1.Cu" signal "GND")
		(6 "In2.Cu" signal "VCC")
		(8 "In3.Cu" signal "VCC1")
		(10 "In4.Cu" signal "GND1")
		(12 "In5.Cu" signal "IN1")
		(14 "In6.Cu" signal "GND2")
		(16 "In7.Cu" signal "IN2")
		(18 "In8.Cu" signal "GND3")
		(20 "In9.Cu" signal "IN3")
		(22 "In10.Cu" signal "GND4")
		(24 "In11.Cu" signal "IN4")
		(26 "In12.Cu" signal "GND5")
		(28 "In13.Cu" signal "IN5")
		(30 "In14.Cu" signal "GND6")
		(32 "In15.Cu" signal "IN6")
		(34 "In16.Cu" signal "GND7")
		(2 "B.Cu" signal "BOTTOM")
		(9 "F.Adhes" user "F.Adhesive")
		(11 "B.Adhes" user "B.Adhesive")
		(13 "F.Paste" user "Package Geometry/Pastemask Top")
		(15 "B.Paste" user "Package Geometry/Pastemask Bottom")
		(5 "F.SilkS" user "Ref Des/Silkscreen Top")
		(7 "B.SilkS" user "Ref Des/Silkscreen Bottom")
		(1 "F.Mask" user "Board Geometry/Soldermask Top")
		(3 "B.Mask" user "Board Geometry/Soldermask Bottom")
		(17 "Dwgs.User" user "User.Drawings")
		(19 "Cmts.User" user "User.Comments")
		(21 "Eco1.User" user "User.Eco1")
		(23 "Eco2.User" user "User.Eco2")
		(25 "Edge.Cuts" user "Board Geometry/Outline")
		(27 "Margin" user)
		(31 "F.CrtYd" user "Package Geometry/Place Bound Top")
		(29 "B.CrtYd" user "Package Geometry/Place Bound Bottom")
		(35 "F.Fab" user "Ref Des/Assembly Top")
		(33 "B.Fab" user "Ref Des/Assembly Bottom")
	)
	(footprint ""
		(layer "F.Cu")
		(at 140.442442 -252.356874 -90)
		(property "Reference" "R1298"
			(at 0 0 270)
			(layer "F.SilkS")
			(hide yes)
			(effects
				(font
					(size 1.27 1.27)
				)
			)
		)
		(property "Value" ""
			(at 0 0 270)
			(layer "F.Fab")
			(effects
				(font
					(size 1.27 1.27)
				)
			)
		)
		(duplicate_pad_numbers_are_jumpers no)
		(fp_line
			(start -0.7874 0.4064)
			(end -0.7874 -0.4064)
			(stroke
				(width 0.1524)
				(type default)
			)
			(layer "F.SilkS")
		)
		(fp_line
			(start 0.7874 0.4064)
			(end -0.7874 0.4064)
			(stroke
				(width 0.1524)
				(type default)
			)
			(layer "F.SilkS")
		)
		(fp_line
			(start -0.7874 -0.4064)
			(end 0.7874 -0.4064)
			(stroke
				(width 0.1524)
				(type default)
			)
			(layer "F.SilkS")
		)
		(fp_line
			(start 0.7874 -0.4064)
			(end 0.7874 0.4064)
			(stroke
				(width 0.1524)
				(type default)
			)
			(layer "F.SilkS")
		)
		(fp_line
			(start -0.67945 0.3048)
			(end -0.67945 -0.305054)
			(stroke
				(width 0.1)
				(type default)
			)
			(layer "F.Fab")
		)
		(fp_line
			(start -0.12065 0.3048)
			(end -0.67945 0.3048)
			(stroke
				(width 0.1)
				(type default)
			)
			(layer "F.Fab")
		)
		(fp_line
			(start 0.120396 0.3048)
			(end 0.120396 0.2794)
			(stroke
				(width 0.1)
				(type default)
			)
			(layer "F.Fab")
		)
		(fp_line
			(start 0.67945 0.3048)
			(end 0.120396 0.3048)
			(stroke
				(width 0.1)
				(type default)
			)
			(layer "F.Fab")
		)
		(fp_line
			(start -0.12065 0.2794)
			(end -0.12065 0.3048)
			(stroke
				(width 0.1)
				(type default)
			)
			(layer "F.Fab")
		)
		(fp_line
			(start 0.120396 0.2794)
			(end -0.12065 0.2794)
			(stroke
				(width 0.1)
				(type default)
			)
			(layer "F.Fab")
		)
		(fp_line
			(start -0.12065 -0.2794)
			(end 0.12065 -0.2794)
			(stroke
				(width 0.1)
				(type default)
			)
			(layer "F.Fab")
		)
		(fp_line
			(start 0.12065 -0.2794)
			(end 0.12065 -0.3048)
			(stroke
				(width 0.1)
				(type default)
			)
			(layer "F.Fab")
		)
		(fp_line
			(start 0.12065 -0.3048)
			(end 0.67945 -0.3048)
			(stroke
				(width 0.1)
				(type default)
			)
			(layer "F.Fab")
		)
		(fp_line
			(start 0.67945 -0.3048)
			(end 0.67945 0.3048)
			(stroke
				(width 0.1)
				(type default)
			)
			(layer "F.Fab")
		)
		(fp_line
			(start -0.67945 -0.305054)
			(end -0.12065 -0.305054)
			(stroke
				(width 0.1)
				(type default)
			)
			(layer "F.Fab")
		)
		(fp_line
			(start -0.12065 -0.305054)
			(end -0.12065 -0.2794)
			(stroke
				(width 0.1)
				(type default)
			)
			(layer "F.Fab")
		)
		(pad "1" smd circle
			(at -0.40005 0 270)
			(size 0 0)
			(layers "F.Cu" "F.Mask" "F.Paste")
			(net "GND")
		)
		(pad "2" smd circle
			(at 0.40005 0 270)
			(size 0 0)
			(layers "F.Cu" "F.Mask" "F.Paste")
			(net "PEX1_MODE_SEL9")
		)
	)
	(footprint ""
		(layer "F.Cu")
		(at 315.04763 -40.037258 90)
		(property "Reference" "U377"
			(at 0.297942 2.40284 90)
			(unlocked yes)
			(layer "F.SilkS")
			(effects
				(font
					(size 0.7874 0.5842)
					(thickness 0.1524)
				)
			)
		)
		(property "Value" ""
			(at 0 0 90)
			(layer "F.Fab")
			(effects
				(font
					(size 1.27 1.27)
				)
			)
		)
		(duplicate_pad_numbers_are_jumpers no)
		(fp_line
			(start -1.949958 -1.610106)
			(end 1.949958 -1.610106)
			(stroke
				(width 0.1524)
				(type default)
			)
			(layer "F.SilkS")
		)
		(fp_line
			(start 1.949958 -1.560068)
			(end 1.949958 1.610106)
			(stroke
				(width 0.1524)
				(type default)
			)
			(layer "F.SilkS")
		)
		(fp_line
			(start 1.949958 1.610106)
			(end -1.949958 1.610106)
			(stroke
				(width 0.1524)
				(type default)
			)
			(layer "F.SilkS")
		)
		(fp_line
			(start -1.949958 1.610106)
			(end -1.949958 -1.610106)
			(stroke
				(width 0.1524)
				(type default)
			)
			(layer "F.SilkS")
		)
		(fp_line
			(start 0.750062 -1.560068)
			(end 0.750062 1.560068)
			(stroke
				(width 0.1)
				(type default)
			)
			(layer "F.Fab")
		)
		(fp_line
			(start -0.750062 -1.560068)
			(end 0.750062 -1.560068)
			(stroke
				(width 0.1)
				(type default)
			)
			(layer "F.Fab")
		)
		(fp_line
			(start 0.750062 1.560068)
			(end -0.750062 1.560068)
			(stroke
				(width 0.1)
				(type default)
			)
			(layer "F.Fab")
		)
		(fp_line
			(start -0.750062 1.560068)
			(end -0.750062 -1.560068)
			(stroke
				(width 0.1)
				(type default)
			)
			(layer "F.Fab")
		)
		(pad "D" smd rect
			(at 1.100074 0)
			(size 1.016 1.4224)
			(layers "F.Cu" "F.Mask" "F.Paste")
			(net "SSD11_AUX_P3V3_EN")
		)
		(pad "G" smd rect
			(at -1.100074 -0.94996)
			(size 1.016 1.4224)
			(layers "F.Cu" "F.Mask" "F.Paste")
			(net "PRSNT_SSD11_R1_N")
		)
		(pad "S" smd rect
			(at -1.100074 0.94996)
			(size 1.016 1.4224)
			(layers "F.Cu" "F.Mask" "F.Paste")
			(net "GND")
		)
	)
	(footprint ""
		(layer "F.Cu")
		(at 196.550788 -414.45815 -90)
		(property "Reference" "C4477"
			(at 0 0 270)
			(layer "F.SilkS")
			(hide yes)
			(effects
				(font
					(size 1.27 1.27)
				)
			)
		)
		(property "Value" ""
			(at 0 0 270)
			(layer "F.Fab")
			(effects
				(font
					(size 1.27 1.27)
				)
			)
		)
		(duplicate_pad_numbers_are_jumpers no)
		(fp_line
			(start -0.7874 0.4064)
			(end -0.7874 -0.4064)
			(stroke
				(width 0.1524)
				(type default)
			)
			(layer "F.SilkS")
		)
		(fp_line
			(start 0.7874 0.4064)
			(end -0.7874 0.4064)
			(stroke
				(width 0.1524)
				(type default)
			)
			(layer "F.SilkS")
		)
		(fp_line
			(start -0.7874 -0.4064)
			(end 0.7874 -0.4064)
			(stroke
				(width 0.1524)
				(type default)
			)
			(layer "F.SilkS")
		)
		(fp_line
			(start 0.7874 -0.4064)
			(end 0.7874 0.4064)
			(stroke
				(width 0.1524)
				(type default)
			)
			(layer "F.SilkS")
		)
		(fp_line
			(start -0.67945 0.3048)
			(end -0.67945 -0.305054)
			(stroke
				(width 0.1)
				(type default)
			)
			(layer "F.Fab")
		)
		(fp_line
			(start -0.12065 0.3048)
			(end -0.67945 0.3048)
			(stroke
				(width 0.1)
				(type default)
			)
			(layer "F.Fab")
		)
		(fp_line
			(start 0.120396 0.3048)
			(end 0.120396 0.2794)
			(stroke
				(width 0.1)
				(type default)
			)
			(layer "F.Fab")
		)
		(fp_line
			(start 0.67945 0.3048)
			(end 0.120396 0.3048)
			(stroke
				(width 0.1)
				(type default)
			)
			(layer "F.Fab")
		)
		(fp_line
			(start -0.12065 0.2794)
			(end -0.12065 0.3048)
			(stroke
				(width 0.1)
				(type default)
			)
			(layer "F.Fab")
		)
		(fp_line
			(start 0.120396 0.2794)
			(end -0.12065 0.2794)
			(stroke
				(width 0.1)
				(type default)
			)
			(layer "F.Fab")
		)
		(fp_line
			(start -0.12065 -0.2794)
			(end 0.12065 -0.2794)
			(stroke
				(width 0.1)
				(type default)
			)
			(layer "F.Fab")
		)
		(fp_line
			(start 0.12065 -0.2794)
			(end 0.12065 -0.3048)
			(stroke
				(width 0.1)
				(type default)
			)
			(layer "F.Fab")
		)
		(fp_line
			(start 0.12065 -0.3048)
			(end 0.67945 -0.3048)
			(stroke
				(width 0.1)
				(type default)
			)
			(layer "F.Fab")
		)
		(fp_line
			(start 0.67945 -0.3048)
			(end 0.67945 0.3048)
			(stroke
				(width 0.1)
				(type default)
			)
			(layer "F.Fab")
		)
		(fp_line
			(start -0.67945 -0.305054)
			(end -0.12065 -0.305054)
			(stroke
				(width 0.1)
				(type default)
			)
			(layer "F.Fab")
		)
		(fp_line
			(start -0.12065 -0.305054)
			(end -0.12065 -0.2794)
			(stroke
				(width 0.1)
				(type default)
			)
			(layer "F.Fab")
		)
		(pad "1" smd circle
			(at -0.40005 0 270)
			(size 0 0)
			(layers "F.Cu" "F.Mask" "F.Paste")
			(net "UV_P2V5_COMP")
		)
		(pad "2" smd circle
			(at 0.40005 0 270)
			(size 0 0)
			(layers "F.Cu" "F.Mask" "F.Paste")
			(net "GND")
		)
	)
	(footprint ""
		(layer "F.Cu")
		(at 235.871512 -234.728004 -90)
		(property "Reference" "R6189"
			(at 0 0 270)
			(layer "F.SilkS")
			(hide yes)
			(effects
				(font
					(size 1.27 1.27)
				)
			)
		)
		(property "Value" ""
			(at 0 0 270)
			(layer "F.Fab")
			(effects
				(font
					(size 1.27 1.27)
				)
			)
		)
		(duplicate_pad_numbers_are_jumpers no)
		(fp_line
			(start -0.7874 0.4064)
			(end -0.7874 -0.4064)
			(stroke
				(width 0.1524)
				(type default)
			)
			(layer "F.SilkS")
		)
		(fp_line
			(start 0.7874 0.4064)
			(end -0.7874 0.4064)
			(stroke
				(width 0.1524)
				(type default)
			)
			(layer "F.SilkS")
		)
		(fp_line
			(start -0.7874 -0.4064)
			(end 0.7874 -0.4064)
			(stroke
				(width 0.1524)
				(type default)
			)
			(layer "F.SilkS")
		)
		(fp_line
			(start 0.7874 -0.4064)
			(end 0.7874 0.4064)
			(stroke
				(width 0.1524)
				(type default)
			)
			(layer "F.SilkS")
		)
		(fp_line
			(start -0.67945 0.3048)
			(end -0.67945 -0.305054)
			(stroke
				(width 0.1)
				(type default)
			)
			(layer "F.Fab")
		)
		(fp_line
			(start -0.12065 0.3048)
			(end -0.67945 0.3048)
			(stroke
				(width 0.1)
				(type default)
			)
			(layer "F.Fab")
		)
		(fp_line
			(start 0.120396 0.3048)
			(end 0.120396 0.2794)
			(stroke
				(width 0.1)
				(type default)
			)
			(layer "F.Fab")
		)
		(fp_line
			(start 0.67945 0.3048)
			(end 0.120396 0.3048)
			(stroke
				(width 0.1)
				(type default)
			)
			(layer "F.Fab")
		)
		(fp_line
			(start -0.12065 0.2794)
			(end -0.12065 0.3048)
			(stroke
				(width 0.1)
				(type default)
			)
			(layer "F.Fab")
		)
		(fp_line
			(start 0.120396 0.2794)
			(end -0.12065 0.2794)
			(stroke
				(width 0.1)
				(type default)
			)
			(layer "F.Fab")
		)
		(fp_line
			(start -0.12065 -0.2794)
			(end 0.12065 -0.2794)
			(stroke
				(width 0.1)
				(type default)
			)
			(layer "F.Fab")
		)
		(fp_line
			(start 0.12065 -0.2794)
			(end 0.12065 -0.3048)
			(stroke
				(width 0.1)
				(type default)
			)
			(layer "F.Fab")
		)
		(fp_line
			(start 0.12065 -0.3048)
			(end 0.67945 -0.3048)
			(stroke
				(width 0.1)
				(type default)
			)
			(layer "F.Fab")
		)
		(fp_line
			(start 0.67945 -0.3048)
			(end 0.67945 0.3048)
			(stroke
				(width 0.1)
				(type default)
			)
			(layer "F.Fab")
		)
		(fp_line
			(start -0.67945 -0.305054)
			(end -0.12065 -0.305054)
			(stroke
				(width 0.1)
				(type default)
			)
			(layer "F.Fab")
		)
		(fp_line
			(start -0.12065 -0.305054)
			(end -0.12065 -0.2794)
			(stroke
				(width 0.1)
				(type default)
			)
			(layer "F.Fab")
		)
		(pad "1" smd circle
			(at -0.40005 0 270)
			(size 0 0)
			(layers "F.Cu" "F.Mask" "F.Paste")
			(net "GND")
		)
		(pad "2" smd circle
			(at 0.40005 0 270)
			(size 0 0)
			(layers "F.Cu" "F.Mask" "F.Paste")
			(net "SSD7_PWRDIS_BIC_R")
		)
	)
	(footprint ""
		(layer "F.Cu")
		(at 380.711456 -283.643832 -90)
		(property "Reference" "R4595"
			(at 0 0 270)
			(layer "F.SilkS")
			(hide yes)
			(effects
				(font
					(size 1.27 1.27)
				)
			)
		)
		(property "Value" ""
			(at 0 0 270)
			(layer "F.Fab")
			(effects
				(font
					(size 1.27 1.27)
				)
			)
		)
		(duplicate_pad_numbers_are_jumpers no)
		(fp_line
			(start -0.7874 0.4064)
			(end -0.7874 -0.4064)
			(stroke
				(width 0.1524)
				(type default)
			)
			(layer "F.SilkS")
		)
		(fp_line
			(start 0.7874 0.4064)
			(end -0.7874 0.4064)
			(stroke
				(width 0.1524)
				(type default)
			)
			(layer "F.SilkS")
		)
		(fp_line
			(start -0.7874 -0.4064)
			(end 0.7874 -0.4064)
			(stroke
				(width 0.1524)
				(type default)
			)
			(layer "F.SilkS")
		)
		(fp_line
			(start 0.7874 -0.4064)
			(end 0.7874 0.4064)
			(stroke
				(width 0.1524)
				(type default)
			)
			(layer "F.SilkS")
		)
		(fp_line
			(start -0.67945 0.3048)
			(end -0.67945 -0.305054)
			(stroke
				(width 0.1)
				(type default)
			)
			(layer "F.Fab")
		)
		(fp_line
			(start -0.12065 0.3048)
			(end -0.67945 0.3048)
			(stroke
				(width 0.1)
				(type default)
			)
			(layer "F.Fab")
		)
		(fp_line
			(start 0.120396 0.3048)
			(end 0.120396 0.2794)
			(stroke
				(width 0.1)
				(type default)
			)
			(layer "F.Fab")
		)
		(fp_line
			(start 0.67945 0.3048)
			(end 0.120396 0.3048)
			(stroke
				(width 0.1)
				(type default)
			)
			(layer "F.Fab")
		)
		(fp_line
			(start -0.12065 0.2794)
			(end -0.12065 0.3048)
			(stroke
				(width 0.1)
				(type default)
			)
			(layer "F.Fab")
		)
		(fp_line
			(start 0.120396 0.2794)
			(end -0.12065 0.2794)
			(stroke
				(width 0.1)
				(type default)
			)
			(layer "F.Fab")
		)
		(fp_line
			(start -0.12065 -0.2794)
			(end 0.12065 -0.2794)
			(stroke
				(width 0.1)
				(type default)
			)
			(layer "F.Fab")
		)
		(fp_line
			(start 0.12065 -0.2794)
			(end 0.12065 -0.3048)
			(stroke
				(width 0.1)
				(type default)
			)
			(layer "F.Fab")
		)
		(fp_line
			(start 0.12065 -0.3048)
			(end 0.67945 -0.3048)
			(stroke
				(width 0.1)
				(type default)
			)
			(layer "F.Fab")
		)
		(fp_line
			(start 0.67945 -0.3048)
			(end 0.67945 0.3048)
			(stroke
				(width 0.1)
				(type default)
			)
			(layer "F.Fab")
		)
		(fp_line
			(start -0.67945 -0.305054)
			(end -0.12065 -0.305054)
			(stroke
				(width 0.1)
				(type default)
			)
			(layer "F.Fab")
		)
		(fp_line
			(start -0.12065 -0.305054)
			(end -0.12065 -0.2794)
			(stroke
				(width 0.1)
				(type default)
			)
			(layer "F.Fab")
		)
		(pad "1" smd circle
			(at -0.40005 0 270)
			(size 0 0)
			(layers "F.Cu" "F.Mask" "F.Paste")
			(net "PCEPLL7_VDDA18_PEX3")
		)
		(pad "2" smd circle
			(at 0.40005 0 270)
			(size 0 0)
			(layers "F.Cu" "F.Mask" "F.Paste")
			(net "PCEPLL7_VDDA18_PEX3_R")
		)
	)
	(footprint ""
		(layer "F.Cu")
		(at 219.202 -203.2)
		(property "Reference" "R1515"
			(at 0 0 0)
			(layer "F.SilkS")
			(hide yes)
			(effects
				(font
					(size 1.27 1.27)
				)
			)
		)
		(property "Value" ""
			(at 0 0 0)
			(layer "F.Fab")
			(effects
				(font
					(size 1.27 1.27)
				)
			)
		)
		(duplicate_pad_numbers_are_jumpers no)
		(fp_line
			(start -0.7874 -0.4064)
			(end 0.7874 -0.4064)
			(stroke
				(width 0.1524)
				(type default)
			)
			(layer "F.SilkS")
		)
		(fp_line
			(start -0.7874 0.4064)
			(end -0.7874 -0.4064)
			(stroke
				(width 0.1524)
				(type default)
			)
			(layer "F.SilkS")
		)
		(fp_line
			(start 0.7874 -0.4064)
			(end 0.7874 0.4064)
			(stroke
				(width 0.1524)
				(type default)
			)
			(layer "F.SilkS")
		)
		(fp_line
			(start 0.7874 0.4064)
			(end -0.7874 0.4064)
			(stroke
				(width 0.1524)
				(type default)
			)
			(layer "F.SilkS")
		)
		(fp_line
			(start -0.67945 -0.305054)
			(end -0.12065 -0.305054)
			(stroke
				(width 0.1)
				(type default)
			)
			(layer "F.Fab")
		)
		(fp_line
			(start -0.67945 0.3048)
			(end -0.67945 -0.305054)
			(stroke
				(width 0.1)
				(type default)
			)
			(layer "F.Fab")
		)
		(fp_line
			(start -0.12065 -0.305054)
			(end -0.12065 -0.2794)
			(stroke
				(width 0.1)
				(type default)
			)
			(layer "F.Fab")
		)
		(fp_line
			(start -0.12065 -0.2794)
			(end 0.12065 -0.2794)
			(stroke
				(width 0.1)
				(type default)
			)
			(layer "F.Fab")
		)
		(fp_line
			(start -0.12065 0.2794)
			(end -0.12065 0.3048)
			(stroke
				(width 0.1)
				(type default)
			)
			(layer "F.Fab")
		)
		(fp_line
			(start -0.12065 0.3048)
			(end -0.67945 0.3048)
			(stroke
				(width 0.1)
				(type default)
			)
			(layer "F.Fab")
		)
		(fp_line
			(start 0.120396 0.2794)
			(end -0.12065 0.2794)
			(stroke
				(width 0.1)
				(type default)
			)
			(layer "F.Fab")
		)
		(fp_line
			(start 0.120396 0.3048)
			(end 0.120396 0.2794)
			(stroke
				(width 0.1)
				(type default)
			)
			(layer "F.Fab")
		)
		(fp_line
			(start 0.12065 -0.3048)
			(end 0.67945 -0.3048)
			(stroke
				(width 0.1)
				(type default)
			)
			(layer "F.Fab")
		)
		(fp_line
			(start 0.12065 -0.2794)
			(end 0.12065 -0.3048)
			(stroke
				(width 0.1)
				(type default)
			)
			(layer "F.Fab")
		)
		(fp_line
			(start 0.67945 -0.3048)
			(end 0.67945 0.3048)
			(stroke
				(width 0.1)
				(type default)
			)
			(layer "F.Fab")
		)
		(fp_line
			(start 0.67945 0.3048)
			(end 0.120396 0.3048)
			(stroke
				(width 0.1)
				(type default)
			)
			(layer "F.Fab")
		)
		(pad "1" smd circle
			(at -0.40005 0)
			(size 0 0)
			(layers "F.Cu" "F.Mask" "F.Paste")
			(net "SMB_NIC5_LS_R_SDA")
		)
		(pad "2" smd circle
			(at 0.40005 0)
			(size 0 0)
			(layers "F.Cu" "F.Mask" "F.Paste")
			(net "P3V3_NIC5")
		)
	)
)
